(kicad_pcb
	(version 20260206)
	(generator "pcbnew")
	(generator_version "10.0")
	(general
		(thickness 1.6)
		(legacy_teardrops no)
	)
	(paper "A4")
	(title_block
		(title "peb — Lightning_PEB_BRD.brd")
		(comment 1 "Lightning (Wiwynn / Facebook NVMe JBOF) / footprints 1550-1556 of 2563")
	)
	(layers
		(0 "F.Cu" signal "TOP")
		(4 "In1.Cu" signal "L2GND")
		(6 "In2.Cu" signal "L3")
		(8 "In3.Cu" signal "L4VCC")
		(10 "In4.Cu" signal "L5VCC")
		(12 "In5.Cu" signal "L6")
		(14 "In6.Cu" signal "L7GND")
		(2 "B.Cu" signal "BOTTOM")
		(9 "F.Adhes" user "F.Adhesive")
		(11 "B.Adhes" user "B.Adhesive")
		(13 "F.Paste" user "Package Geometry/Pastemask Top")
		(15 "B.Paste" user "Package Geometry/Pastemask Bottom")
		(5 "F.SilkS" user "Ref Des/Silkscreen Top")
		(7 "B.SilkS" user "Ref Des/Silkscreen Bottom")
		(1 "F.Mask" user "Board Geometry/Soldermask Top")
		(3 "B.Mask" user "Board Geometry/Soldermask Bottom")
		(17 "Dwgs.User" user "User.Drawings")
		(19 "Cmts.User" user "User.Comments")
		(21 "Eco1.User" user "User.Eco1")
		(23 "Eco2.User" user "User.Eco2")
		(25 "Edge.Cuts" user "Board Geometry/Outline")
		(27 "Margin" user)
		(31 "F.CrtYd" user "Package Geometry/Place Bound Top")
		(29 "B.CrtYd" user "Package Geometry/Place Bound Bottom")
		(35 "F.Fab" user "Ref Des/Assembly Top")
		(33 "B.Fab" user "Ref Des/Assembly Bottom")
	)
	(footprint ""
		(layer "F.Cu")
		(at 66.7766 -109.7534)
		(property "Reference" "R312"
			(at 0 0 0)
			(layer "F.SilkS")
			(hide yes)
			(effects
				(font
					(size 1.27 1.27)
				)
			)
		)
		(property "Value" "4K7R2F-GP"
			(at 0.064008 -3.993896 0)
			(unlocked yes)
			(layer "F.Fab")
			(hide yes)
			(effects
				(font
					(size 1.016 1.016)
					(thickness 0.1524)
				)
			)
		)
		(property "Device Type" "R402H16"
			(at 0.064008 -5.517896 0)
			(unlocked yes)
			(layer "F.Fab")
			(hide yes)
			(effects
				(font
					(size 1.016 1.016)
					(thickness 0.1524)
				)
			)
		)
		(duplicate_pad_numbers_are_jumpers no)
		(fp_line
			(start -0.508 -0.9398)
			(end -0.508 0.9398)
			(stroke
				(width 0.1524)
				(type default)
			)
			(layer "F.SilkS")
		)
		(fp_line
			(start 0.508 -0.9398)
			(end -0.508 -0.9398)
			(stroke
				(width 0.1524)
				(type default)
			)
			(layer "F.SilkS")
		)
		(fp_rect
			(start -0.508 0.9398)
			(end 0.508 -0.9398)
			(stroke
				(width 0)
				(type default)
			)
			(fill no)
			(layer "F.CrtYd")
		)
		(fp_rect
			(start -0.508 0.9398)
			(end 0.508 -0.9398)
			(stroke
				(width 0)
				(type default)
			)
			(fill no)
			(layer "F.Fab")
		)
		(pad "1" smd custom
			(at 0 -0.4445)
			(size 0.1397 0.1397)
			(layers "F.Cu" "F.Mask" "F.Paste")
			(net "P3V3_STBY")
			(options
				(clearance outline)
				(anchor circle)
			)
			(primitives
				(gr_poly
					(pts
						(arc
							(start -0.1778 -0.2794)
							(mid -0.249642 -0.249642)
							(end -0.2794 -0.1778)
						)
						(arc
							(start -0.2794 0.1778)
							(mid -0.249642 0.249642)
							(end -0.1778 0.2794)
						)
						(arc
							(start 0.1778 0.2794)
							(mid 0.249642 0.249642)
							(end 0.2794 0.1778)
						)
						(arc
							(start 0.2794 -0.1778)
							(mid 0.249642 -0.249642)
							(end 0.1778 -0.2794)
						)
					)
					(width 0)
					(fill yes)
				)
			)
		)
		(pad "2" smd custom
			(at 0 0.4445)
			(size 0.1397 0.1397)
			(layers "F.Cu" "F.Mask" "F.Paste")
			(net "I2C5_LS_G2")
			(options
				(clearance outline)
				(anchor circle)
			)
			(primitives
				(gr_poly
					(pts
						(arc
							(start -0.1778 -0.2794)
							(mid -0.249642 -0.249642)
							(end -0.2794 -0.1778)
						)
						(arc
							(start -0.2794 0.1778)
							(mid -0.249642 0.249642)
							(end -0.1778 0.2794)
						)
						(arc
							(start 0.1778 0.2794)
							(mid 0.249642 0.249642)
							(end 0.2794 0.1778)
						)
						(arc
							(start 0.2794 -0.1778)
							(mid 0.249642 -0.249642)
							(end 0.1778 -0.2794)
						)
					)
					(width 0)
					(fill yes)
				)
			)
		)
	)
	(footprint ""
		(layer "F.Cu")
		(at 19.809714 -92.72905 90)
		(property "Reference" "R2938"
			(at 0 0 90)
			(layer "F.SilkS")
			(hide yes)
			(effects
				(font
					(size 1.27 1.27)
				)
			)
		)
		(property "Value" "0R2J-2-GP"
			(at 0.064008 -3.993896 90)
			(unlocked yes)
			(layer "F.Fab")
			(hide yes)
			(effects
				(font
					(size 1.016 1.016)
					(thickness 0.1524)
				)
			)
		)
		(property "Device Type" "R402H16"
			(at 0.064008 -5.517896 90)
			(unlocked yes)
			(layer "F.Fab")
			(hide yes)
			(effects
				(font
					(size 1.016 1.016)
					(thickness 0.1524)
				)
			)
		)
		(duplicate_pad_numbers_are_jumpers no)
		(fp_line
			(start 0.508 -0.9398)
			(end -0.508 -0.9398)
			(stroke
				(width 0.1524)
				(type default)
			)
			(layer "F.SilkS")
		)
		(fp_line
			(start -0.508 -0.9398)
			(end -0.508 0.9398)
			(stroke
				(width 0.1524)
				(type default)
			)
			(layer "F.SilkS")
		)
		(fp_rect
			(start -0.508 0.9398)
			(end 0.508 -0.9398)
			(stroke
				(width 0)
				(type default)
			)
			(fill no)
			(layer "F.CrtYd")
		)
		(fp_rect
			(start -0.508 0.9398)
			(end 0.508 -0.9398)
			(stroke
				(width 0)
				(type default)
			)
			(fill no)
			(layer "F.Fab")
		)
		(pad "1" smd custom
			(at 0 -0.4445 90)
			(size 0.1397 0.1397)
			(layers "F.Cu" "F.Mask" "F.Paste")
			(net "BMC_TPM_RST")
			(options
				(clearance outline)
				(anchor circle)
			)
			(primitives
				(gr_poly
					(pts
						(arc
							(start -0.1778 -0.2794)
							(mid -0.249642 -0.249642)
							(end -0.2794 -0.1778)
						)
						(arc
							(start -0.2794 0.1778)
							(mid -0.249642 0.249642)
							(end -0.1778 0.2794)
						)
						(arc
							(start 0.1778 0.2794)
							(mid 0.249642 0.249642)
							(end 0.2794 0.1778)
						)
						(arc
							(start 0.2794 -0.1778)
							(mid 0.249642 -0.249642)
							(end 0.1778 -0.2794)
						)
					)
					(width 0)
					(fill yes)
				)
			)
		)
		(pad "2" smd custom
			(at 0 0.4445 90)
			(size 0.1397 0.1397)
			(layers "F.Cu" "F.Mask" "F.Paste")
			(net "FM_TPM_PRES_RST_N")
			(options
				(clearance outline)
				(anchor circle)
			)
			(primitives
				(gr_poly
					(pts
						(arc
							(start -0.1778 -0.2794)
							(mid -0.249642 -0.249642)
							(end -0.2794 -0.1778)
						)
						(arc
							(start -0.2794 0.1778)
							(mid -0.249642 0.249642)
							(end -0.1778 0.2794)
						)
						(arc
							(start 0.1778 0.2794)
							(mid 0.249642 0.249642)
							(end 0.2794 0.1778)
						)
						(arc
							(start 0.2794 -0.1778)
							(mid 0.249642 -0.249642)
							(end 0.1778 -0.2794)
						)
					)
					(width 0)
					(fill yes)
				)
			)
		)
	)
	(footprint ""
		(layer "F.Cu")
		(at 192.8368 -28.6512 -90)
		(property "Reference" "C142"
			(at 0 0 270)
			(layer "F.SilkS")
			(hide yes)
			(effects
				(font
					(size 1.27 1.27)
				)
			)
		)
		(property "Value" "SCD047U25V2KX-GP"
			(at 1.1811 -2.7051 270)
			(unlocked yes)
			(layer "F.Fab")
			(hide yes)
			(effects
				(font
					(size 1.016 1.016)
					(thickness 0.1524)
				)
			)
		)
		(property "Device Type" "C402H22"
			(at 1.1811 -4.2291 270)
			(unlocked yes)
			(layer "F.Fab")
			(hide yes)
			(effects
				(font
					(size 1.016 1.016)
					(thickness 0.1524)
				)
			)
		)
		(duplicate_pad_numbers_are_jumpers no)
		(fp_rect
			(start -0.4318 0.9525)
			(end 0.4318 -0.9525)
			(stroke
				(width 0)
				(type default)
			)
			(fill no)
			(layer "F.CrtYd")
		)
		(fp_rect
			(start -0.4318 0.9525)
			(end 0.4318 -0.9525)
			(stroke
				(width 0)
				(type default)
			)
			(fill no)
			(layer "F.Fab")
		)
		(pad "1" smd custom
			(at 0 -0.4445 270)
			(size 0.1524 0.1524)
			(layers "F.Cu" "F.Mask" "F.Paste")
			(net "P3V3_STBY")
			(options
				(clearance outline)
				(anchor circle)
			)
			(primitives
				(gr_poly
					(pts
						(arc
							(start 0.3048 -0.2032)
							(mid 0.275042 -0.275042)
							(end 0.2032 -0.3048)
						)
						(arc
							(start -0.2032 -0.3048)
							(mid -0.275042 -0.275042)
							(end -0.3048 -0.2032)
						)
						(arc
							(start -0.3048 0.2032)
							(mid -0.275042 0.275042)
							(end -0.2032 0.3048)
						)
						(arc
							(start 0.2032 0.3048)
							(mid 0.275042 0.275042)
							(end 0.3048 0.2032)
						)
					)
					(width 0)
					(fill yes)
				)
			)
		)
		(pad "2" smd custom
			(at 0 0.4445 270)
			(size 0.1524 0.1524)
			(layers "F.Cu" "F.Mask" "F.Paste")
			(net "GND")
			(options
				(clearance outline)
				(anchor circle)
			)
			(primitives
				(gr_poly
					(pts
						(arc
							(start 0.3048 -0.2032)
							(mid 0.275042 -0.275042)
							(end 0.2032 -0.3048)
						)
						(arc
							(start -0.2032 -0.3048)
							(mid -0.275042 -0.275042)
							(end -0.3048 -0.2032)
						)
						(arc
							(start -0.3048 0.2032)
							(mid -0.275042 0.275042)
							(end -0.2032 0.3048)
						)
						(arc
							(start 0.2032 0.3048)
							(mid 0.275042 0.275042)
							(end 0.3048 0.2032)
						)
					)
					(width 0)
					(fill yes)
				)
			)
		)
	)
	(footprint ""
		(layer "F.Cu")
		(at 45.623734 -152.002744 90)
		(property "Reference" "C200"
			(at 0 0 90)
			(layer "F.SilkS")
			(hide yes)
			(effects
				(font
					(size 1.27 1.27)
				)
			)
		)
		(property "Value" "SC1U10V2KX-4-GP"
			(at 1.1811 -2.7051 90)
			(unlocked yes)
			(layer "F.Fab")
			(hide yes)
			(effects
				(font
					(size 1.016 1.016)
					(thickness 0.1524)
				)
			)
		)
		(property "Device Type" "C402H22"
			(at 1.1811 -4.2291 90)
			(unlocked yes)
			(layer "F.Fab")
			(hide yes)
			(effects
				(font
					(size 1.016 1.016)
					(thickness 0.1524)
				)
			)
		)
		(duplicate_pad_numbers_are_jumpers no)
		(fp_rect
			(start -0.4318 0.9525)
			(end 0.4318 -0.9525)
			(stroke
				(width 0)
				(type default)
			)
			(fill no)
			(layer "F.CrtYd")
		)
		(fp_rect
			(start -0.4318 0.9525)
			(end 0.4318 -0.9525)
			(stroke
				(width 0)
				(type default)
			)
			(fill no)
			(layer "F.Fab")
		)
		(pad "1" smd custom
			(at 0 -0.4445 90)
			(size 0.1524 0.1524)
			(layers "F.Cu" "F.Mask" "F.Paste")
			(net "P1V53_STBY")
			(options
				(clearance outline)
				(anchor circle)
			)
			(primitives
				(gr_poly
					(pts
						(arc
							(start 0.3048 -0.2032)
							(mid 0.275042 -0.275042)
							(end 0.2032 -0.3048)
						)
						(arc
							(start -0.2032 -0.3048)
							(mid -0.275042 -0.275042)
							(end -0.3048 -0.2032)
						)
						(arc
							(start -0.3048 0.2032)
							(mid -0.275042 0.275042)
							(end -0.2032 0.3048)
						)
						(arc
							(start 0.2032 0.3048)
							(mid 0.275042 0.275042)
							(end 0.3048 0.2032)
						)
					)
					(width 0)
					(fill yes)
				)
			)
		)
		(pad "2" smd custom
			(at 0 0.4445 90)
			(size 0.1524 0.1524)
			(layers "F.Cu" "F.Mask" "F.Paste")
			(net "GND")
			(options
				(clearance outline)
				(anchor circle)
			)
			(primitives
				(gr_poly
					(pts
						(arc
							(start 0.3048 -0.2032)
							(mid 0.275042 -0.275042)
							(end 0.2032 -0.3048)
						)
						(arc
							(start -0.2032 -0.3048)
							(mid -0.275042 -0.275042)
							(end -0.3048 -0.2032)
						)
						(arc
							(start -0.3048 0.2032)
							(mid -0.275042 0.275042)
							(end -0.2032 0.3048)
						)
						(arc
							(start 0.2032 0.3048)
							(mid 0.275042 0.275042)
							(end 0.3048 0.2032)
						)
					)
					(width 0)
					(fill yes)
				)
			)
		)
	)
	(footprint ""
		(layer "F.Cu")
		(at 74.168 -42.291 90)
		(property "Reference" "PL3"
			(at 0 0 90)
			(layer "F.SilkS")
			(hide yes)
			(effects
				(font
					(size 1.27 1.27)
				)
			)
		)
		(property "Value" "COIL-1D5UH-32-GP"
			(at -4.699 -4.0132 90)
			(unlocked yes)
			(layer "F.Fab")
			(hide yes)
			(effects
				(font
					(size 1.016 1.016)
					(thickness 0.1524)
				)
			)
		)
		(property "Device Type" "L7066-1830-UH119"
			(at -4.699 -5.5372 90)
			(unlocked yes)
			(layer "F.Fab")
			(hide yes)
			(effects
				(font
					(size 1.016 1.016)
					(thickness 0.1524)
				)
			)
		)
		(duplicate_pad_numbers_are_jumpers no)
		(fp_line
			(start 3.556 -4.4958)
			(end 3.556 4.4958)
			(stroke
				(width 0.1524)
				(type default)
			)
			(layer "F.SilkS")
		)
		(fp_line
			(start -3.556 -4.4958)
			(end 3.556 -4.4958)
			(stroke
				(width 0.1524)
				(type default)
			)
			(layer "F.SilkS")
		)
		(fp_line
			(start 3.556 4.4958)
			(end -3.556 4.4958)
			(stroke
				(width 0.1524)
				(type default)
			)
			(layer "F.SilkS")
		)
		(fp_line
			(start -3.556 4.4958)
			(end -3.556 -4.4958)
			(stroke
				(width 0.1524)
				(type default)
			)
			(layer "F.SilkS")
		)
		(fp_rect
			(start -3.302 3.4798)
			(end 3.302 -3.4798)
			(stroke
				(width 0)
				(type default)
			)
			(fill no)
			(layer "F.CrtYd")
		)
		(fp_poly
			(pts
				(xy -3.81 4.572) (xy -3.81 -4.572) (xy 3.81 -4.572) (xy 3.81 -0.5588) (xy 3.302 -0.5588) (xy 3.302 -3.4798)
				(xy -3.302 -3.4798) (xy -3.302 3.4798) (xy 3.302 3.4798) (xy 3.302 -0.5461) (xy 3.81 -0.5461) (xy 3.81 4.572)
			)
			(stroke
				(width 0)
				(type default)
			)
			(fill no)
			(layer "F.CrtYd")
		)
		(fp_rect
			(start -3.81 4.572)
			(end 3.81 -4.572)
			(stroke
				(width 0)
				(type default)
			)
			(fill no)
			(layer "F.Fab")
		)
		(pad "1" smd rect
			(at 0 -2.779522 90)
			(size 3.5052 2.921)
			(layers "F.Cu" "F.Mask" "F.Paste")
			(net "P3V3_STBY_LL")
		)
		(pad "2" smd rect
			(at 0 2.779522 90)
			(size 3.5052 2.921)
			(layers "F.Cu" "F.Mask" "F.Paste")
			(net "P3V3_PWR")
		)
	)
	(footprint ""
		(layer "F.Cu")
		(at 11.1506 -76.6318 180)
		(property "Reference" "C377"
			(at 0 0 180)
			(layer "F.SilkS")
			(hide yes)
			(effects
				(font
					(size 1.27 1.27)
				)
			)
		)
		(property "Value" "SCD039U16V2KX-GP"
			(at 1.1811 -2.7051 180)
			(unlocked yes)
			(layer "F.Fab")
			(hide yes)
			(effects
				(font
					(size 1.016 1.016)
					(thickness 0.1524)
				)
			)
		)
		(property "Device Type" "C402H22"
			(at 1.1811 -4.2291 180)
			(unlocked yes)
			(layer "F.Fab")
			(hide yes)
			(effects
				(font
					(size 1.016 1.016)
					(thickness 0.1524)
				)
			)
		)
		(duplicate_pad_numbers_are_jumpers no)
		(fp_rect
			(start -0.4318 0.9525)
			(end 0.4318 -0.9525)
			(stroke
				(width 0)
				(type default)
			)
			(fill no)
			(layer "F.CrtYd")
		)
		(fp_rect
			(start -0.4318 0.9525)
			(end 0.4318 -0.9525)
			(stroke
				(width 0)
				(type default)
			)
			(fill no)
			(layer "F.Fab")
		)
		(pad "1" smd custom
			(at 0 -0.4445 180)
			(size 0.1524 0.1524)
			(layers "F.Cu" "F.Mask" "F.Paste")
			(net "I210_CTOP")
			(options
				(clearance outline)
				(anchor circle)
			)
			(primitives
				(gr_poly
					(pts
						(arc
							(start 0.3048 -0.2032)
							(mid 0.275042 -0.275042)
							(end 0.2032 -0.3048)
						)
						(arc
							(start -0.2032 -0.3048)
							(mid -0.275042 -0.275042)
							(end -0.3048 -0.2032)
						)
						(arc
							(start -0.3048 0.2032)
							(mid -0.275042 0.275042)
							(end -0.2032 0.3048)
						)
						(arc
							(start 0.2032 0.3048)
							(mid 0.275042 0.275042)
							(end 0.3048 0.2032)
						)
					)
					(width 0)
					(fill yes)
				)
			)
		)
		(pad "2" smd custom
			(at 0 0.4445 180)
			(size 0.1524 0.1524)
			(layers "F.Cu" "F.Mask" "F.Paste")
			(net "I210_CBOT")
			(options
				(clearance outline)
				(anchor circle)
			)
			(primitives
				(gr_poly
					(pts
						(arc
							(start 0.3048 -0.2032)
							(mid 0.275042 -0.275042)
							(end 0.2032 -0.3048)
						)
						(arc
							(start -0.2032 -0.3048)
							(mid -0.275042 -0.275042)
							(end -0.3048 -0.2032)
						)
						(arc
							(start -0.3048 0.2032)
							(mid -0.275042 0.275042)
							(end -0.2032 0.3048)
						)
						(arc
							(start 0.2032 0.3048)
							(mid 0.275042 0.275042)
							(end 0.3048 0.2032)
						)
					)
					(width 0)
					(fill yes)
				)
			)
		)
	)
	(footprint ""
		(layer "F.Cu")
		(at 194.3862 -26.8986 180)
		(property "Reference" "R833"
			(at 0 0 180)
			(layer "F.SilkS")
			(hide yes)
			(effects
				(font
					(size 1.27 1.27)
				)
			)
		)
		(property "Value" "4K7R2F-GP"
			(at 0.064008 -3.993896 180)
			(unlocked yes)
			(layer "F.Fab")
			(hide yes)
			(effects
				(font
					(size 1.016 1.016)
					(thickness 0.1524)
				)
			)
		)
		(property "Device Type" "R402H16"
			(at 0.064008 -5.517896 180)
			(unlocked yes)
			(layer "F.Fab")
			(hide yes)
			(effects
				(font
					(size 1.016 1.016)
					(thickness 0.1524)
				)
			)
		)
		(duplicate_pad_numbers_are_jumpers no)
		(fp_line
			(start 0.508 -0.9398)
			(end -0.508 -0.9398)
			(stroke
				(width 0.1524)
				(type default)
			)
			(layer "F.SilkS")
		)
		(fp_line
			(start -0.508 -0.9398)
			(end -0.508 0.9398)
			(stroke
				(width 0.1524)
				(type default)
			)
			(layer "F.SilkS")
		)
		(fp_rect
			(start -0.508 0.9398)
			(end 0.508 -0.9398)
			(stroke
				(width 0)
				(type default)
			)
			(fill no)
			(layer "F.CrtYd")
		)
		(fp_rect
			(start -0.508 0.9398)
			(end 0.508 -0.9398)
			(stroke
				(width 0)
				(type default)
			)
			(fill no)
			(layer "F.Fab")
		)
		(pad "1" smd custom
			(at 0 -0.4445 180)
			(size 0.1397 0.1397)
			(layers "F.Cu" "F.Mask" "F.Paste")
			(net "U56_A0")
			(options
				(clearance outline)
				(anchor circle)
			)
			(primitives
				(gr_poly
					(pts
						(arc
							(start -0.1778 -0.2794)
							(mid -0.249642 -0.249642)
							(end -0.2794 -0.1778)
						)
						(arc
							(start -0.2794 0.1778)
							(mid -0.249642 0.249642)
							(end -0.1778 0.2794)
						)
						(arc
							(start 0.1778 0.2794)
							(mid 0.249642 0.249642)
							(end 0.2794 0.1778)
						)
						(arc
							(start 0.2794 -0.1778)
							(mid 0.249642 -0.249642)
							(end 0.1778 -0.2794)
						)
					)
					(width 0)
					(fill yes)
				)
			)
		)
		(pad "2" smd custom
			(at 0 0.4445 180)
			(size 0.1397 0.1397)
			(layers "F.Cu" "F.Mask" "F.Paste")
			(net "P3V3_STBY")
			(options
				(clearance outline)
				(anchor circle)
			)
			(primitives
				(gr_poly
					(pts
						(arc
							(start -0.1778 -0.2794)
							(mid -0.249642 -0.249642)
							(end -0.2794 -0.1778)
						)
						(arc
							(start -0.2794 0.1778)
							(mid -0.249642 0.249642)
							(end -0.1778 0.2794)
						)
						(arc
							(start 0.1778 0.2794)
							(mid 0.249642 0.249642)
							(end 0.2794 0.1778)
						)
						(arc
							(start 0.2794 -0.1778)
							(mid 0.249642 -0.249642)
							(end 0.1778 -0.2794)
						)
					)
					(width 0)
					(fill yes)
				)
			)
		)
	)
)
